# BASEBOARD_FAB2 (Tioga Pass) — schematic netlist excerpt (pin names and nets, part order shuffled) for the footprints in the layout excerpt that follows; sources: Cadence DE-HDL packaged netlist, KiCad conversion of Wiwynn_Tioga_Pass_MB.brd

CT65  CAP  1000PF 50V 10% X7R  pkg 0402LF  page 236 : A = VR_PVNN_PCH_PH1_PHASE_SW ; B = VR_PVNN_PCH_PH1_PHASE_SW_RC
C6G5  CAP  10UF 4V 20% X6S  pkg 0603LF  page 231 : A = PVPP_ABC ; B = GND
R25W21  120R2F-GP  1%  pkg RCL_GP  page 151 : \1\ = GND ; \2\ = BMC_M_A9

(kicad_pcb
	(version 20260206)
	(generator "pcbnew")
	(generator_version "10.0")
	(general
		(thickness 1.6)
		(legacy_teardrops no)
	)
	(paper "A4")
	(title_block
		(title "Wiwynn_Tioga_Pass_MB.brd")
		(comment 1 "Tioga Pass / footprints 825-827 of 4770")
	)
	(layers
		(0 "F.Cu" signal "TOP")
		(4 "In1.Cu" signal "L2GND")
		(6 "In2.Cu" signal "L3")
		(8 "In3.Cu" signal "L4GND")
		(10 "In4.Cu" signal "L5")
		(12 "In5.Cu" signal "L6GND")
		(14 "In6.Cu" signal "L7VCC")
		(16 "In7.Cu" signal "L8VCC")
		(18 "In8.Cu" signal "L9GND")
		(20 "In9.Cu" signal "L10")
		(22 "In10.Cu" signal "L11GND")
		(24 "In11.Cu" signal "L12")
		(26 "In12.Cu" signal "L13GND")
		(2 "B.Cu" signal "BOTTOM")
		(9 "F.Adhes" user "F.Adhesive")
		(11 "B.Adhes" user "B.Adhesive")
		(13 "F.Paste" user "Package Geometry/Pastemask Top")
		(15 "B.Paste" user "Package Geometry/Pastemask Bottom")
		(5 "F.SilkS" user "Ref Des/Silkscreen Top")
		(7 "B.SilkS" user "Ref Des/Silkscreen Bottom")
		(1 "F.Mask" user "Board Geometry/Soldermask Top")
		(3 "B.Mask" user "Board Geometry/Soldermask Bottom")
		(17 "Dwgs.User" user "User.Drawings")
		(19 "Cmts.User" user "User.Comments")
		(21 "Eco1.User" user "User.Eco1")
		(23 "Eco2.User" user "User.Eco2")
		(25 "Edge.Cuts" user "Board Geometry/Outline")
		(27 "Margin" user)
		(31 "F.CrtYd" user "Package Geometry/Place Bound Top")
		(29 "B.CrtYd" user "Package Geometry/Place Bound Bottom")
		(35 "F.Fab" user "Ref Des/Assembly Top")
		(33 "B.Fab" user "Ref Des/Assembly Bottom")
	)
	(footprint ""
		(layer "F.Cu")
		(at 372.528338 -146.561048 180)
		(property "Reference" "CT65"
			(at -0.8382 -0.67818 180)
			(unlocked yes)
			(layer "F.SilkS")
			(effects
				(font
					(size 0.4064 0.254)
					(thickness 0.1524)
				)
				(justify left)
			)
		)
		(property "Value" ""
			(at 0 0 180)
			(layer "F.Fab")
			(effects
				(font
					(size 1.27 1.27)
				)
			)
		)
		(duplicate_pad_numbers_are_jumpers no)
		(fp_poly
			(pts
				(xy 0.3048 -0.1016) (xy 0.3048 0.9906) (xy -0.3048 0.9906) (xy -0.3048 -0.1016)
			)
			(stroke
				(width 0)
				(type default)
			)
			(fill no)
			(layer "F.CrtYd")
		)
		(fp_line
			(start 0.3048 0.9906)
			(end 0.3048 -0.1016)
			(stroke
				(width 0.1)
				(type default)
			)
			(layer "F.Fab")
		)
		(fp_line
			(start 0.3048 -0.1016)
			(end -0.3048 -0.1016)
			(stroke
				(width 0.1)
				(type default)
			)
			(layer "F.Fab")
		)
		(fp_line
			(start -0.3048 0.9906)
			(end 0.3048 0.9906)
			(stroke
				(width 0.1)
				(type default)
			)
			(layer "F.Fab")
		)
		(fp_line
			(start -0.3048 -0.1016)
			(end -0.3048 0.9906)
			(stroke
				(width 0.1)
				(type default)
			)
			(layer "F.Fab")
		)
		(pad "1" smd rect
			(at 0 0 180)
			(size 0.508 0.508)
			(layers "F.Cu" "F.Mask" "F.Paste")
			(net "VR_PVNN_PCH_PH1_PHASE_SW")
		)
		(pad "2" smd rect
			(at 0 0.889 180)
			(size 0.508 0.508)
			(layers "F.Cu" "F.Mask" "F.Paste")
			(net "VR_PVNN_PCH_PH1_PHASE_SW_RC")
		)
		(zone
			(layer "F.Cu")
			(hatch none 0.5)
			(connect_pads
				(clearance 0)
			)
			(min_thickness 0.25)
			(keepout
				(tracks not_allowed)
				(vias allowed)
				(pads allowed)
				(copperpour not_allowed)
				(footprints allowed)
			)
			(placement
				(enabled no)
				(sheetname "")
			)
			(fill
				(thermal_gap 0.5)
				(thermal_bridge_width 0.5)
				(island_removal_mode 0)
			)
			(polygon
				(pts
					(xy 372.782338 -147.196048) (xy 372.274338 -147.196048) (xy 372.274338 -146.815048) (xy 372.782338 -146.815048)
				)
			)
		)
		(zone
			(layer "F.Cu")
			(hatch none 0.5)
			(connect_pads
				(clearance 0)
			)
			(min_thickness 0.25)
			(keepout
				(tracks allowed)
				(vias not_allowed)
				(pads allowed)
				(copperpour not_allowed)
				(footprints allowed)
			)
			(placement
				(enabled no)
				(sheetname "")
			)
			(fill
				(thermal_gap 0.5)
				(thermal_bridge_width 0.5)
				(island_removal_mode 0)
			)
			(polygon
				(pts
					(xy 372.782338 -146.815048) (xy 372.274338 -146.815048) (xy 372.274338 -147.196048) (xy 372.782338 -147.196048)
				)
			)
		)
	)
	(footprint ""
		(layer "F.Cu")
		(at 320.194432 -3.302 90)
		(property "Reference" "C6G5"
			(at 0 0 90)
			(layer "F.SilkS")
			(hide yes)
			(effects
				(font
					(size 1.27 1.27)
				)
			)
		)
		(property "Value" ""
			(at 0 0 90)
			(layer "F.Fab")
			(effects
				(font
					(size 1.27 1.27)
				)
			)
		)
		(duplicate_pad_numbers_are_jumpers no)
		(fp_poly
			(pts
				(xy -0.4953 -0.2032) (xy 0.4953 -0.2032) (xy 0.4953 1.6002) (xy -0.4953 1.6002)
			)
			(stroke
				(width 0)
				(type default)
			)
			(fill no)
			(layer "F.CrtYd")
		)
		(fp_line
			(start 0.4953 -0.2032)
			(end 0.4953 1.6002)
			(stroke
				(width 0.1)
				(type default)
			)
			(layer "F.Fab")
		)
		(fp_line
			(start -0.4953 -0.2032)
			(end 0.4953 -0.2032)
			(stroke
				(width 0.1)
				(type default)
			)
			(layer "F.Fab")
		)
		(fp_line
			(start 0.4953 1.6002)
			(end -0.4953 1.6002)
			(stroke
				(width 0.1)
				(type default)
			)
			(layer "F.Fab")
		)
		(fp_line
			(start -0.4953 1.6002)
			(end -0.4953 -0.2032)
			(stroke
				(width 0.1)
				(type default)
			)
			(layer "F.Fab")
		)
		(pad "1" smd rect
			(at 0 0 90)
			(size 0.762 0.889)
			(layers "F.Cu" "F.Mask" "F.Paste")
			(net "PVPP_ABC")
		)
		(pad "2" smd rect
			(at 0 1.397 90)
			(size 0.762 0.889)
			(layers "F.Cu" "F.Mask" "F.Paste")
			(net "GND")
		)
		(zone
			(layer "F.Cu")
			(hatch none 0.5)
			(connect_pads
				(clearance 0)
			)
			(min_thickness 0.25)
			(keepout
				(tracks not_allowed)
				(vias allowed)
				(pads allowed)
				(copperpour not_allowed)
				(footprints allowed)
			)
			(placement
				(enabled no)
				(sheetname "")
			)
			(fill
				(thermal_gap 0.5)
				(thermal_bridge_width 0.5)
				(island_removal_mode 0)
			)
			(polygon
				(pts
					(xy 320.638932 -2.921) (xy 320.638932 -3.683) (xy 321.146932 -3.683) (xy 321.146932 -2.921)
				)
			)
		)
	)
	(footprint ""
		(layer "F.Cu")
		(at 438.833006 -41.663874 180)
		(property "Reference" "R25W21"
			(at 0 0 180)
			(layer "F.SilkS")
			(hide yes)
			(effects
				(font
					(size 1.27 1.27)
				)
			)
		)
		(property "Value" "*"
			(at 0.064008 -4.108196 180)
			(unlocked yes)
			(layer "F.Fab")
			(hide yes)
			(effects
				(font
					(size 1.27 1.016)
					(thickness 0.1524)
				)
			)
		)
		(property "Device Type" "120R2F-GP_RCL_GP-120R2F-GP,64.A"
			(at 0.064008 -5.632196 180)
			(unlocked yes)
			(layer "F.Fab")
			(hide yes)
			(effects
				(font
					(size 1.27 1.016)
					(thickness 0.1524)
				)
			)
		)
		(duplicate_pad_numbers_are_jumpers no)
		(fp_line
			(start 0.508 -0.9398)
			(end -0.508 -0.9398)
			(stroke
				(width 0.1524)
				(type default)
			)
			(layer "F.SilkS")
		)
		(fp_line
			(start -0.508 -0.9398)
			(end -0.508 0.9398)
			(stroke
				(width 0.1524)
				(type default)
			)
			(layer "F.SilkS")
		)
		(fp_rect
			(start -0.508 0.9398)
			(end 0.508 -0.9398)
			(stroke
				(width 0)
				(type default)
			)
			(fill no)
			(layer "F.CrtYd")
		)
		(fp_rect
			(start -0.508 0.9398)
			(end 0.508 -0.9398)
			(stroke
				(width 0)
				(type default)
			)
			(fill no)
			(layer "F.Fab")
		)
		(pad "1" smd custom
			(at 0 -0.4445 180)
			(size 0.1397 0.1397)
			(layers "F.Cu" "F.Mask" "F.Paste")
			(net "GND")
			(options
				(clearance outline)
				(anchor circle)
			)
			(primitives
				(gr_poly
					(pts
						(arc
							(start -0.1778 -0.2794)
							(mid -0.249642 -0.249642)
							(end -0.2794 -0.1778)
						)
						(arc
							(start -0.2794 0.1778)
							(mid -0.249642 0.249642)
							(end -0.1778 0.2794)
						)
						(arc
							(start 0.1778 0.2794)
							(mid 0.249642 0.249642)
							(end 0.2794 0.1778)
						)
						(arc
							(start 0.2794 -0.1778)
							(mid 0.249642 -0.249642)
							(end 0.1778 -0.2794)
						)
					)
					(width 0)
					(fill yes)
				)
			)
		)
		(pad "2" smd custom
			(at 0 0.4445 180)
			(size 0.1397 0.1397)
			(layers "F.Cu" "F.Mask" "F.Paste")
			(net "BMC_M_A9")
			(options
				(clearance outline)
				(anchor circle)
			)
			(primitives
				(gr_poly
					(pts
						(arc
							(start -0.1778 -0.2794)
							(mid -0.249642 -0.249642)
							(end -0.2794 -0.1778)
						)
						(arc
							(start -0.2794 0.1778)
							(mid -0.249642 0.249642)
							(end -0.1778 0.2794)
						)
						(arc
							(start 0.1778 0.2794)
							(mid 0.249642 0.249642)
							(end 0.2794 0.1778)
						)
						(arc
							(start 0.2794 -0.1778)
							(mid 0.249642 -0.249642)
							(end 0.1778 -0.2794)
						)
					)
					(width 0)
					(fill yes)
				)
			)
		)
	)
)
